(kicad_pcb
	(version 20260206)
	(generator "pcbnew")
	(generator_version "10.0")
	(general
		(thickness 1.6)
		(legacy_teardrops no)
	)
	(paper "A4")
	(title_block
		(title "v1-chassis-manager — T6M_CM_d_v01_1031_1645.brd")
		(comment 1 "Open CloudServer (Microsoft) / footprints 2082-2091 of 2512")
	)
	(layers
		(0 "F.Cu" signal "TOP")
		(4 "In1.Cu" signal "GND1")
		(6 "In2.Cu" signal "IN1")
		(8 "In3.Cu" signal "VCC1")
		(10 "In4.Cu" signal "VCC2")
		(12 "In5.Cu" signal "GND2")
		(14 "In6.Cu" signal "IN2")
		(16 "In7.Cu" signal "IN3")
		(18 "In8.Cu" signal "GND3")
		(2 "B.Cu" signal "BOTTOM")
		(9 "F.Adhes" user "F.Adhesive")
		(11 "B.Adhes" user "B.Adhesive")
		(13 "F.Paste" user "Package Geometry/Pastemask Top")
		(15 "B.Paste" user "Package Geometry/Pastemask Bottom")
		(5 "F.SilkS" user "Ref Des/Silkscreen Top")
		(7 "B.SilkS" user "Ref Des/Silkscreen Bottom")
		(1 "F.Mask" user "Board Geometry/Soldermask Top")
		(3 "B.Mask" user "Board Geometry/Soldermask Bottom")
		(17 "Dwgs.User" user "User.Drawings")
		(19 "Cmts.User" user "User.Comments")
		(21 "Eco1.User" user "User.Eco1")
		(23 "Eco2.User" user "User.Eco2")
		(25 "Edge.Cuts" user "Board Geometry/Outline")
		(27 "Margin" user)
		(31 "F.CrtYd" user "Package Geometry/Place Bound Top")
		(29 "B.CrtYd" user "Package Geometry/Place Bound Bottom")
		(35 "F.Fab" user "Ref Des/Assembly Top")
		(33 "B.Fab" user "Ref Des/Assembly Bottom")
	)
	(footprint ""
		(layer "B.Cu")
		(at 106.788458 -174.156116 180)
		(property "Reference" "R704"
			(at -1.765046 -0.685292 270)
			(unlocked yes)
			(layer "B.SilkS")
			(effects
				(font
					(size 0.7874 0.5842)
					(thickness 0.1524)
				)
				(justify left mirror)
			)
		)
		(property "Value" ""
			(at 0 0 0)
			(layer "B.Fab")
			(effects
				(font
					(size 1.27 1.27)
				)
				(justify mirror)
			)
		)
		(duplicate_pad_numbers_are_jumpers no)
		(fp_line
			(start 0.7874 0.4064)
			(end 0.7874 -0.4064)
			(stroke
				(width 0.1524)
				(type default)
			)
			(layer "B.SilkS")
		)
		(fp_line
			(start 0.7874 -0.4064)
			(end -0.7874 -0.4064)
			(stroke
				(width 0.1524)
				(type default)
			)
			(layer "B.SilkS")
		)
		(fp_line
			(start -0.7874 0.4064)
			(end 0.7874 0.4064)
			(stroke
				(width 0.1524)
				(type default)
			)
			(layer "B.SilkS")
		)
		(fp_line
			(start -0.7874 -0.4064)
			(end -0.7874 0.4064)
			(stroke
				(width 0.1524)
				(type default)
			)
			(layer "B.SilkS")
		)
		(fp_poly
			(pts
				(xy 0.508 0.2794) (xy 0.508 0.2286) (xy 0.635 0.2286) (xy 0.635 -0.254) (xy 0.5334 -0.254) (xy 0.5334 -0.2794)
				(xy -0.5334 -0.2794) (xy -0.5334 -0.254) (xy -0.635 -0.254) (xy -0.635 0.254) (xy -0.5334 0.254)
				(xy -0.5334 0.2794)
			)
			(stroke
				(width 0)
				(type default)
			)
			(fill no)
			(layer "B.CrtYd")
		)
		(pad "1" smd rect
			(at -0.40005 0)
			(size 0.4572 0.508)
			(layers "B.Cu" "B.Mask" "B.Paste")
			(net "P3V3_NODE1")
		)
		(pad "2" smd rect
			(at 0.40005 0)
			(size 0.4572 0.508)
			(layers "B.Cu" "B.Mask" "B.Paste")
			(net "N21698979")
		)
	)
	(footprint ""
		(layer "B.Cu")
		(at 37.929312 -157.23489 180)
		(property "Reference" "C407"
			(at 6.960616 9.003792 0)
			(unlocked yes)
			(layer "B.SilkS")
			(effects
				(font
					(size 0.7874 0.5842)
					(thickness 0.1524)
				)
				(justify left mirror)
			)
		)
		(property "Value" ""
			(at 0 0 0)
			(layer "B.Fab")
			(effects
				(font
					(size 1.27 1.27)
				)
				(justify mirror)
			)
		)
		(duplicate_pad_numbers_are_jumpers no)
		(fp_line
			(start 0.7874 0.4064)
			(end 0.7874 -0.4064)
			(stroke
				(width 0.1524)
				(type default)
			)
			(layer "B.SilkS")
		)
		(fp_line
			(start 0.7874 -0.4064)
			(end -0.7874 -0.4064)
			(stroke
				(width 0.1524)
				(type default)
			)
			(layer "B.SilkS")
		)
		(fp_line
			(start 0 0.381)
			(end 0 -0.381)
			(stroke
				(width 0.1524)
				(type default)
			)
			(layer "B.SilkS")
		)
		(fp_line
			(start -0.7874 0.4064)
			(end 0.7874 0.4064)
			(stroke
				(width 0.1524)
				(type default)
			)
			(layer "B.SilkS")
		)
		(fp_line
			(start -0.7874 -0.4064)
			(end -0.7874 0.4064)
			(stroke
				(width 0.1524)
				(type default)
			)
			(layer "B.SilkS")
		)
		(fp_poly
			(pts
				(xy 0.5334 0.254) (xy 0.635 0.254) (xy 0.635 0.2286) (xy 0.635 -0.254) (xy 0.5334 -0.254) (xy 0.5334 -0.2794)
				(xy -0.5334 -0.2794) (xy -0.5334 -0.254) (xy -0.635 -0.254) (xy -0.635 0.254) (xy -0.5334 0.254)
				(xy -0.5334 0.2794) (xy 0.508 0.2794) (xy 0.5334 0.2794)
			)
			(stroke
				(width 0)
				(type default)
			)
			(fill no)
			(layer "B.CrtYd")
		)
		(pad "1" smd rect
			(at -0.40005 0)
			(size 0.4572 0.508)
			(layers "B.Cu" "B.Mask" "B.Paste")
			(net "P1V9_LAN1")
		)
		(pad "2" smd rect
			(at 0.40005 0)
			(size 0.4572 0.508)
			(layers "B.Cu" "B.Mask" "B.Paste")
			(net "GND")
		)
	)
	(footprint ""
		(layer "B.Cu")
		(at 60.42914 -70.133718 90)
		(property "Reference" "C62"
			(at -32.210248 -10.29589 270)
			(unlocked yes)
			(layer "B.SilkS")
			(effects
				(font
					(size 0.7874 0.5842)
					(thickness 0.1524)
				)
				(justify left mirror)
			)
		)
		(property "Value" ""
			(at 0 0 90)
			(layer "B.Fab")
			(effects
				(font
					(size 1.27 1.27)
				)
				(justify mirror)
			)
		)
		(duplicate_pad_numbers_are_jumpers no)
		(fp_line
			(start 0.7874 -0.4064)
			(end -0.7874 -0.4064)
			(stroke
				(width 0.1524)
				(type default)
			)
			(layer "B.SilkS")
		)
		(fp_line
			(start -0.7874 -0.4064)
			(end -0.7874 0.4064)
			(stroke
				(width 0.1524)
				(type default)
			)
			(layer "B.SilkS")
		)
		(fp_line
			(start 0 0.381)
			(end 0 -0.381)
			(stroke
				(width 0.1524)
				(type default)
			)
			(layer "B.SilkS")
		)
		(fp_line
			(start 0.7874 0.4064)
			(end 0.7874 -0.4064)
			(stroke
				(width 0.1524)
				(type default)
			)
			(layer "B.SilkS")
		)
		(fp_line
			(start -0.7874 0.4064)
			(end 0.7874 0.4064)
			(stroke
				(width 0.1524)
				(type default)
			)
			(layer "B.SilkS")
		)
		(fp_poly
			(pts
				(xy 0.5334 0.254) (xy 0.635 0.254) (xy 0.635 0.2286) (xy 0.635 -0.254) (xy 0.5334 -0.254) (xy 0.5334 -0.2794)
				(xy -0.5334 -0.2794) (xy -0.5334 -0.254) (xy -0.635 -0.254) (xy -0.635 0.254) (xy -0.5334 0.254)
				(xy -0.5334 0.2794) (xy 0.508 0.2794) (xy 0.5334 0.2794)
			)
			(stroke
				(width 0)
				(type default)
			)
			(fill no)
			(layer "B.CrtYd")
		)
		(pad "1" smd rect
			(at -0.40005 0 270)
			(size 0.4572 0.508)
			(layers "B.Cu" "B.Mask" "B.Paste")
			(net "P1V05_VCCPLL_DDR3_NODE1")
		)
		(pad "2" smd rect
			(at 0.40005 0 270)
			(size 0.4572 0.508)
			(layers "B.Cu" "B.Mask" "B.Paste")
			(net "GND")
		)
	)
	(footprint ""
		(layer "B.Cu")
		(at 71.175372 -80.514698 90)
		(property "Reference" "C72"
			(at -32.158686 -14.55039 270)
			(unlocked yes)
			(layer "B.SilkS")
			(effects
				(font
					(size 0.7874 0.5842)
					(thickness 0.1524)
				)
				(justify left mirror)
			)
		)
		(property "Value" ""
			(at 0 0 90)
			(layer "B.Fab")
			(effects
				(font
					(size 1.27 1.27)
				)
				(justify mirror)
			)
		)
		(duplicate_pad_numbers_are_jumpers no)
		(fp_line
			(start 0.7874 -0.4064)
			(end -0.7874 -0.4064)
			(stroke
				(width 0.1524)
				(type default)
			)
			(layer "B.SilkS")
		)
		(fp_line
			(start -0.7874 -0.4064)
			(end -0.7874 0.4064)
			(stroke
				(width 0.1524)
				(type default)
			)
			(layer "B.SilkS")
		)
		(fp_line
			(start 0 0.381)
			(end 0 -0.381)
			(stroke
				(width 0.1524)
				(type default)
			)
			(layer "B.SilkS")
		)
		(fp_line
			(start 0.7874 0.4064)
			(end 0.7874 -0.4064)
			(stroke
				(width 0.1524)
				(type default)
			)
			(layer "B.SilkS")
		)
		(fp_line
			(start -0.7874 0.4064)
			(end 0.7874 0.4064)
			(stroke
				(width 0.1524)
				(type default)
			)
			(layer "B.SilkS")
		)
		(fp_poly
			(pts
				(xy 0.5334 0.254) (xy 0.635 0.254) (xy 0.635 0.2286) (xy 0.635 -0.254) (xy 0.5334 -0.254) (xy 0.5334 -0.2794)
				(xy -0.5334 -0.2794) (xy -0.5334 -0.254) (xy -0.635 -0.254) (xy -0.635 0.254) (xy -0.5334 0.254)
				(xy -0.5334 0.2794) (xy 0.508 0.2794) (xy 0.5334 0.2794)
			)
			(stroke
				(width 0)
				(type default)
			)
			(fill no)
			(layer "B.CrtYd")
		)
		(pad "1" smd rect
			(at -0.40005 0 270)
			(size 0.4572 0.508)
			(layers "B.Cu" "B.Mask" "B.Paste")
			(net "PV_VCCP_NODE1")
		)
		(pad "2" smd rect
			(at 0.40005 0 270)
			(size 0.4572 0.508)
			(layers "B.Cu" "B.Mask" "B.Paste")
			(net "GND")
		)
	)
	(footprint ""
		(layer "B.Cu")
		(at 103.329994 -115.01882)
		(property "Reference" "PC113"
			(at -2.577846 0.01651 0)
			(unlocked yes)
			(layer "B.SilkS")
			(effects
				(font
					(size 0.7874 0.5842)
					(thickness 0.1524)
				)
				(justify left mirror)
			)
		)
		(property "Value" ""
			(at 0 0 0)
			(layer "B.Fab")
			(effects
				(font
					(size 1.27 1.27)
				)
				(justify mirror)
			)
		)
		(duplicate_pad_numbers_are_jumpers no)
		(fp_line
			(start -1.905 -0.8636)
			(end -1.905 0.8636)
			(stroke
				(width 0.1524)
				(type default)
			)
			(layer "B.SilkS")
		)
		(fp_line
			(start -1.905 0.8636)
			(end 1.905 0.8636)
			(stroke
				(width 0.1524)
				(type default)
			)
			(layer "B.SilkS")
		)
		(fp_line
			(start 0 0.8382)
			(end 0 -0.8382)
			(stroke
				(width 0.1524)
				(type default)
			)
			(layer "B.SilkS")
		)
		(fp_line
			(start 1.905 -0.8636)
			(end -1.905 -0.8636)
			(stroke
				(width 0.1524)
				(type default)
			)
			(layer "B.SilkS")
		)
		(fp_line
			(start 1.905 0.8636)
			(end 1.905 -0.8636)
			(stroke
				(width 0.1524)
				(type default)
			)
			(layer "B.SilkS")
		)
		(fp_rect
			(start 1.524 0.7366)
			(end -1.524 -0.7366)
			(stroke
				(width 0)
				(type default)
			)
			(fill no)
			(layer "B.CrtYd")
		)
		(pad "1" smd rect
			(at -0.94996 0 180)
			(size 1.1176 1.3716)
			(layers "B.Cu" "B.Mask" "B.Paste")
			(net "GND")
		)
		(pad "2" smd rect
			(at 0.94996 0 180)
			(size 1.1176 1.3716)
			(layers "B.Cu" "B.Mask" "B.Paste")
			(net "PV_VCCP_NODE1")
		)
	)
	(footprint ""
		(layer "B.Cu")
		(at 63.231014 -74.678286)
		(property "Reference" "C130"
			(at -13.807694 30.18409 0)
			(unlocked yes)
			(layer "B.SilkS")
			(effects
				(font
					(size 0.7874 0.5842)
					(thickness 0.1524)
				)
				(justify left mirror)
			)
		)
		(property "Value" ""
			(at 0 0 0)
			(layer "B.Fab")
			(effects
				(font
					(size 1.27 1.27)
				)
				(justify mirror)
			)
		)
		(duplicate_pad_numbers_are_jumpers no)
		(fp_line
			(start -0.7874 -0.4064)
			(end -0.7874 0.4064)
			(stroke
				(width 0.1524)
				(type default)
			)
			(layer "B.SilkS")
		)
		(fp_line
			(start -0.7874 0.4064)
			(end 0.7874 0.4064)
			(stroke
				(width 0.1524)
				(type default)
			)
			(layer "B.SilkS")
		)
		(fp_line
			(start 0 0.381)
			(end 0 -0.381)
			(stroke
				(width 0.1524)
				(type default)
			)
			(layer "B.SilkS")
		)
		(fp_line
			(start 0.7874 -0.4064)
			(end -0.7874 -0.4064)
			(stroke
				(width 0.1524)
				(type default)
			)
			(layer "B.SilkS")
		)
		(fp_line
			(start 0.7874 0.4064)
			(end 0.7874 -0.4064)
			(stroke
				(width 0.1524)
				(type default)
			)
			(layer "B.SilkS")
		)
		(fp_poly
			(pts
				(xy 0.5334 0.254) (xy 0.635 0.254) (xy 0.635 0.2286) (xy 0.635 -0.254) (xy 0.5334 -0.254) (xy 0.5334 -0.2794)
				(xy -0.5334 -0.2794) (xy -0.5334 -0.254) (xy -0.635 -0.254) (xy -0.635 0.254) (xy -0.5334 0.254)
				(xy -0.5334 0.2794) (xy 0.508 0.2794) (xy 0.5334 0.2794)
			)
			(stroke
				(width 0)
				(type default)
			)
			(fill no)
			(layer "B.CrtYd")
		)
		(pad "1" smd rect
			(at -0.40005 0 180)
			(size 0.4572 0.508)
			(layers "B.Cu" "B.Mask" "B.Paste")
			(net "P1V05_NODE1")
		)
		(pad "2" smd rect
			(at 0.40005 0 180)
			(size 0.4572 0.508)
			(layers "B.Cu" "B.Mask" "B.Paste")
			(net "GND")
		)
	)
	(footprint ""
		(layer "B.Cu")
		(at 171.180252 -99.66579)
		(property "Reference" "C379"
			(at 7.70509 -0.00381 0)
			(unlocked yes)
			(layer "B.SilkS")
			(effects
				(font
					(size 0.7874 0.5842)
					(thickness 0.1524)
				)
				(justify left mirror)
			)
		)
		(property "Value" ""
			(at 0 0 0)
			(layer "B.Fab")
			(effects
				(font
					(size 1.27 1.27)
				)
				(justify mirror)
			)
		)
		(duplicate_pad_numbers_are_jumpers no)
		(fp_line
			(start -0.7874 -0.4064)
			(end -0.7874 0.4064)
			(stroke
				(width 0.1524)
				(type default)
			)
			(layer "B.SilkS")
		)
		(fp_line
			(start -0.7874 0.4064)
			(end 0.7874 0.4064)
			(stroke
				(width 0.1524)
				(type default)
			)
			(layer "B.SilkS")
		)
		(fp_line
			(start 0 0.381)
			(end 0 -0.381)
			(stroke
				(width 0.1524)
				(type default)
			)
			(layer "B.SilkS")
		)
		(fp_line
			(start 0.7874 -0.4064)
			(end -0.7874 -0.4064)
			(stroke
				(width 0.1524)
				(type default)
			)
			(layer "B.SilkS")
		)
		(fp_line
			(start 0.7874 0.4064)
			(end 0.7874 -0.4064)
			(stroke
				(width 0.1524)
				(type default)
			)
			(layer "B.SilkS")
		)
		(fp_poly
			(pts
				(xy 0.5334 0.254) (xy 0.635 0.254) (xy 0.635 0.2286) (xy 0.635 -0.254) (xy 0.5334 -0.254) (xy 0.5334 -0.2794)
				(xy -0.5334 -0.2794) (xy -0.5334 -0.254) (xy -0.635 -0.254) (xy -0.635 0.254) (xy -0.5334 0.254)
				(xy -0.5334 0.2794) (xy 0.508 0.2794) (xy 0.5334 0.2794)
			)
			(stroke
				(width 0)
				(type default)
			)
			(fill no)
			(layer "B.CrtYd")
		)
		(pad "1" smd rect
			(at -0.40005 0 180)
			(size 0.4572 0.508)
			(layers "B.Cu" "B.Mask" "B.Paste")
			(net "GND")
		)
		(pad "2" smd rect
			(at 0.40005 0 180)
			(size 0.4572 0.508)
			(layers "B.Cu" "B.Mask" "B.Paste")
			(net "P3V3_NODE1")
		)
	)
	(footprint ""
		(layer "B.Cu")
		(at 48.35398 -178.291744 180)
		(property "Reference" "R688"
			(at -1.274064 -0.998982 0)
			(unlocked yes)
			(layer "B.SilkS")
			(effects
				(font
					(size 0.7874 0.5842)
					(thickness 0.1524)
				)
				(justify left mirror)
			)
		)
		(property "Value" ""
			(at 0 0 0)
			(layer "B.Fab")
			(effects
				(font
					(size 1.27 1.27)
				)
				(justify mirror)
			)
		)
		(duplicate_pad_numbers_are_jumpers no)
		(fp_line
			(start 0.7874 0.4064)
			(end 0.7874 -0.4064)
			(stroke
				(width 0.1524)
				(type default)
			)
			(layer "B.SilkS")
		)
		(fp_line
			(start 0.7874 -0.4064)
			(end -0.7874 -0.4064)
			(stroke
				(width 0.1524)
				(type default)
			)
			(layer "B.SilkS")
		)
		(fp_line
			(start -0.7874 0.4064)
			(end 0.7874 0.4064)
			(stroke
				(width 0.1524)
				(type default)
			)
			(layer "B.SilkS")
		)
		(fp_line
			(start -0.7874 -0.4064)
			(end -0.7874 0.4064)
			(stroke
				(width 0.1524)
				(type default)
			)
			(layer "B.SilkS")
		)
		(fp_poly
			(pts
				(xy 0.508 0.2794) (xy 0.508 0.2286) (xy 0.635 0.2286) (xy 0.635 -0.254) (xy 0.5334 -0.254) (xy 0.5334 -0.2794)
				(xy -0.5334 -0.2794) (xy -0.5334 -0.254) (xy -0.635 -0.254) (xy -0.635 0.254) (xy -0.5334 0.254)
				(xy -0.5334 0.2794)
			)
			(stroke
				(width 0)
				(type default)
			)
			(fill no)
			(layer "B.CrtYd")
		)
		(pad "1" smd rect
			(at -0.40005 0)
			(size 0.4572 0.508)
			(layers "B.Cu" "B.Mask" "B.Paste")
			(net "N21699710")
		)
		(pad "2" smd rect
			(at 0.40005 0)
			(size 0.4572 0.508)
			(layers "B.Cu" "B.Mask" "B.Paste")
			(net "GND")
		)
	)
	(footprint ""
		(layer "B.Cu")
		(at 78.83144 -172.505624 180)
		(property "Reference" "R691"
			(at -30.562296 -20.108164 0)
			(unlocked yes)
			(layer "B.SilkS")
			(effects
				(font
					(size 0.7874 0.5842)
					(thickness 0.1524)
				)
				(justify left mirror)
			)
		)
		(property "Value" ""
			(at 0 0 0)
			(layer "B.Fab")
			(effects
				(font
					(size 1.27 1.27)
				)
				(justify mirror)
			)
		)
		(duplicate_pad_numbers_are_jumpers no)
		(fp_line
			(start 0.7874 0.4064)
			(end 0.7874 -0.4064)
			(stroke
				(width 0.1524)
				(type default)
			)
			(layer "B.SilkS")
		)
		(fp_line
			(start 0.7874 -0.4064)
			(end -0.7874 -0.4064)
			(stroke
				(width 0.1524)
				(type default)
			)
			(layer "B.SilkS")
		)
		(fp_line
			(start -0.7874 0.4064)
			(end 0.7874 0.4064)
			(stroke
				(width 0.1524)
				(type default)
			)
			(layer "B.SilkS")
		)
		(fp_line
			(start -0.7874 -0.4064)
			(end -0.7874 0.4064)
			(stroke
				(width 0.1524)
				(type default)
			)
			(layer "B.SilkS")
		)
		(fp_poly
			(pts
				(xy 0.508 0.2794) (xy 0.508 0.2286) (xy 0.635 0.2286) (xy 0.635 -0.254) (xy 0.5334 -0.254) (xy 0.5334 -0.2794)
				(xy -0.5334 -0.2794) (xy -0.5334 -0.254) (xy -0.635 -0.254) (xy -0.635 0.254) (xy -0.5334 0.254)
				(xy -0.5334 0.2794)
			)
			(stroke
				(width 0)
				(type default)
			)
			(fill no)
			(layer "B.CrtYd")
		)
		(pad "1" smd rect
			(at -0.40005 0)
			(size 0.4572 0.508)
			(layers "B.Cu" "B.Mask" "B.Paste")
			(net "T1_NODE3_EN")
		)
		(pad "2" smd rect
			(at 0.40005 0)
			(size 0.4572 0.508)
			(layers "B.Cu" "B.Mask" "B.Paste")
			(net "P5V_NODE1")
		)
	)
	(footprint ""
		(layer "B.Cu")
		(at 99.943158 -150.322534 180)
		(property "Reference" "PC34"
			(at -1.211326 -1.882394 0)
			(unlocked yes)
			(layer "B.SilkS")
			(effects
				(font
					(size 0.7874 0.5842)
					(thickness 0.1524)
				)
				(justify left mirror)
			)
		)
		(property "Value" ""
			(at 0 0 0)
			(layer "B.Fab")
			(effects
				(font
					(size 1.27 1.27)
				)
				(justify mirror)
			)
		)
		(duplicate_pad_numbers_are_jumpers no)
		(fp_line
			(start 2.2098 0.9398)
			(end 2.2098 -0.9398)
			(stroke
				(width 0.1524)
				(type default)
			)
			(layer "B.SilkS")
		)
		(fp_line
			(start 2.2098 -0.9398)
			(end -2.2098 -0.9398)
			(stroke
				(width 0.1524)
				(type default)
			)
			(layer "B.SilkS")
		)
		(fp_line
			(start 0 -0.9398)
			(end 0 0.9398)
			(stroke
				(width 0.1524)
				(type default)
			)
			(layer "B.SilkS")
		)
		(fp_line
			(start -2.2098 0.9398)
			(end 2.2098 0.9398)
			(stroke
				(width 0.1524)
				(type default)
			)
			(layer "B.SilkS")
		)
		(fp_line
			(start -2.2098 -0.9398)
			(end -2.2098 0.9398)
			(stroke
				(width 0.1524)
				(type default)
			)
			(layer "B.SilkS")
		)
		(fp_poly
			(pts
				(xy 1.6764 0.889) (xy 1.6764 0.7874) (xy 2.0574 0.7874) (xy 2.0574 -0.7874) (xy 1.6764 -0.7874)
				(xy 1.6764 -0.9398) (xy -1.6764 -0.9398) (xy -1.6764 -0.7874) (xy -2.0574 -0.7874) (xy -2.0574 0.7874)
				(xy -1.6764 0.7874) (xy -1.6764 0.9398) (xy 1.6764 0.9398)
			)
			(stroke
				(width 0)
				(type default)
			)
			(fill no)
			(layer "B.CrtYd")
		)
		(fp_line
			(start 1.700022 0.899922)
			(end 1.700022 -0.899922)
			(stroke
				(width 0.1)
				(type default)
			)
			(layer "B.Fab")
		)
		(fp_line
			(start 1.700022 -0.899922)
			(end -1.700022 -0.899922)
			(stroke
				(width 0.1)
				(type default)
			)
			(layer "B.Fab")
		)
		(fp_line
			(start -1.700022 0.899922)
			(end 1.700022 0.899922)
			(stroke
				(width 0.1)
				(type default)
			)
			(layer "B.Fab")
		)
		(fp_line
			(start -1.700022 -0.899922)
			(end -1.700022 0.899922)
			(stroke
				(width 0.1)
				(type default)
			)
			(layer "B.Fab")
		)
		(pad "1" smd rect
			(at -1.4732 0)
			(size 1.1684 1.5748)
			(layers "B.Cu" "B.Mask" "B.Paste")
			(net "P12V_AUX")
		)
		(pad "2" smd rect
			(at 1.4732 0)
			(size 1.1684 1.5748)
			(layers "B.Cu" "B.Mask" "B.Paste")
			(net "GND")
		)
	)
)
